(kicad_pcb
	(version 20260206)
	(generator "pcbnew")
	(generator_version "10.0")
	(general
		(thickness 1.6)
		(legacy_teardrops no)
	)
	(paper "A4")
	(title_block
		(title "Wiwynn_Tioga_Pass_MB.brd")
		(comment 1 "Tioga Pass / footprint 1033 of 4770 (EU9E1), pads 43-65 of 65")
	)
	(layers
		(0 "F.Cu" signal "TOP")
		(4 "In1.Cu" signal "L2GND")
		(6 "In2.Cu" signal "L3")
		(8 "In3.Cu" signal "L4GND")
		(10 "In4.Cu" signal "L5")
		(12 "In5.Cu" signal "L6GND")
		(14 "In6.Cu" signal "L7VCC")
		(16 "In7.Cu" signal "L8VCC")
		(18 "In8.Cu" signal "L9GND")
		(20 "In9.Cu" signal "L10")
		(22 "In10.Cu" signal "L11GND")
		(24 "In11.Cu" signal "L12")
		(26 "In12.Cu" signal "L13GND")
		(2 "B.Cu" signal "BOTTOM")
		(9 "F.Adhes" user "F.Adhesive")
		(11 "B.Adhes" user "B.Adhesive")
		(13 "F.Paste" user "Package Geometry/Pastemask Top")
		(15 "B.Paste" user "Package Geometry/Pastemask Bottom")
		(5 "F.SilkS" user "Ref Des/Silkscreen Top")
		(7 "B.SilkS" user "Ref Des/Silkscreen Bottom")
		(1 "F.Mask" user "Board Geometry/Soldermask Top")
		(3 "B.Mask" user "Board Geometry/Soldermask Bottom")
		(17 "Dwgs.User" user "User.Drawings")
		(19 "Cmts.User" user "User.Comments")
		(21 "Eco1.User" user "User.Eco1")
		(23 "Eco2.User" user "User.Eco2")
		(25 "Edge.Cuts" user "Board Geometry/Outline")
		(27 "Margin" user)
		(31 "F.CrtYd" user "Package Geometry/Place Bound Top")
		(29 "B.CrtYd" user "Package Geometry/Place Bound Bottom")
		(35 "F.Fab" user "Ref Des/Assembly Top")
		(33 "B.Fab" user "Ref Des/Assembly Bottom")
	)
	(footprint ""
		(layer "F.Cu")
		(at 484.251 -43.9674 180)
		(property "Reference" "EU9E1"
			(at 7.2644 -5.49529 0)
			(unlocked yes)
			(layer "F.SilkS")
			(effects
				(font
					(size 0.7874 0.5842)
					(thickness 0.1524)
				)
				(justify left)
			)
		)
		(property "Value" ""
			(at 0 0 180)
			(layer "F.Fab")
			(effects
				(font
					(size 1.27 1.27)
				)
			)
		)
		(duplicate_pad_numbers_are_jumpers no)
		(pad "43" smd custom
			(at 4.3688 -1.249934 180)
			(size 0.0762 0.0762)
			(layers "F.Cu" "F.Mask" "F.Paste")
			(net "RMII_PCH_SPRNGVLLE_ARB_OUT")
			(options
				(clearance outline)
				(anchor circle)
			)
			(primitives
				(gr_poly
					(pts
						(xy 0.381 0.1524)
						(arc
							(start -0.2286 0.1524)
							(mid -0.381 0)
							(end -0.2286 -0.1524)
						)
						(xy 0.381 -0.1524)
					)
					(width 0)
					(fill yes)
				)
			)
		)
		(pad "44" smd custom
			(at 4.3688 -1.75006 180)
			(size 0.0762 0.0762)
			(layers "F.Cu" "F.Mask" "F.Paste")
			(net "RMII_PCH_SPRNGVLLE_ARB_IN_R")
			(options
				(clearance outline)
				(anchor circle)
			)
			(primitives
				(gr_poly
					(pts
						(xy 0.381 0.1524)
						(arc
							(start -0.2286 0.1524)
							(mid -0.381 0)
							(end -0.2286 -0.1524)
						)
						(xy 0.381 -0.1524)
					)
					(width 0)
					(fill yes)
				)
			)
		)
		(pad "45" smd custom
			(at 4.3688 -2.249932 180)
			(size 0.0762 0.0762)
			(layers "F.Cu" "F.Mask" "F.Paste")
			(net "XTAL_25MHZ_OUT")
			(options
				(clearance outline)
				(anchor circle)
			)
			(primitives
				(gr_poly
					(pts
						(xy 0.381 0.1524)
						(arc
							(start -0.2286 0.1524)
							(mid -0.381 0)
							(end -0.2286 -0.1524)
						)
						(xy 0.381 -0.1524)
					)
					(width 0)
					(fill yes)
				)
			)
		)
		(pad "46" smd custom
			(at 4.3688 -2.750058 180)
			(size 0.0762 0.0762)
			(layers "F.Cu" "F.Mask" "F.Paste")
			(net "XTAL_25MHZ_IN_R")
			(options
				(clearance outline)
				(anchor circle)
			)
			(primitives
				(gr_poly
					(pts
						(xy 0.381 0.1524)
						(arc
							(start -0.2286 0.1524)
							(mid -0.381 0)
							(end -0.2286 -0.1524)
						)
						(xy 0.381 -0.1524)
					)
					(width 0)
					(fill yes)
				)
			)
		)
		(pad "47" smd custom
			(at 4.3688 -3.24993 180)
			(size 0.0762 0.0762)
			(layers "F.Cu" "F.Mask" "F.Paste")
			(net "P1V5_LAN")
			(options
				(clearance outline)
				(anchor circle)
			)
			(primitives
				(gr_poly
					(pts
						(xy 0.381 0.1524)
						(arc
							(start -0.2286 0.1524)
							(mid -0.381 0)
							(end -0.2286 -0.1524)
						)
						(xy 0.381 -0.1524)
					)
					(width 0)
					(fill yes)
				)
			)
		)
		(pad "48" smd custom
			(at 4.3688 -3.750056 180)
			(size 0.0762 0.0762)
			(layers "F.Cu" "F.Mask" "F.Paste")
			(net "PD_SPRV_RSET")
			(options
				(clearance outline)
				(anchor circle)
			)
			(primitives
				(gr_poly
					(pts
						(xy 0.381 0.1524)
						(arc
							(start -0.2286 0.1524)
							(mid -0.381 0)
							(end -0.2286 -0.1524)
						)
						(xy 0.381 -0.1524)
					)
					(width 0)
					(fill yes)
				)
			)
		)
		(pad "49" smd custom
			(at 3.750056 -4.3688 180)
			(size 0.0762 0.0762)
			(layers "F.Cu" "F.Mask" "F.Paste")
			(net "NIC_SER_N_MDI_3_DN")
			(options
				(clearance outline)
				(anchor circle)
			)
			(primitives
				(gr_poly
					(pts
						(xy 0.1524 -0.381)
						(arc
							(start 0.1524 0.2286)
							(mid 0 0.381)
							(end -0.1524 0.2286)
						)
						(xy -0.1524 -0.381)
					)
					(width 0)
					(fill yes)
				)
			)
		)
		(pad "50" smd custom
			(at 3.24993 -4.3688 180)
			(size 0.0762 0.0762)
			(layers "F.Cu" "F.Mask" "F.Paste")
			(net "NIC_SER_P_MDI_3_DP")
			(options
				(clearance outline)
				(anchor circle)
			)
			(primitives
				(gr_poly
					(pts
						(xy 0.1524 -0.381)
						(arc
							(start 0.1524 0.2286)
							(mid 0 0.381)
							(end -0.1524 0.2286)
						)
						(xy -0.1524 -0.381)
					)
					(width 0)
					(fill yes)
				)
			)
		)
		(pad "51" smd custom
			(at 2.750058 -4.3688 180)
			(size 0.0762 0.0762)
			(layers "F.Cu" "F.Mask" "F.Paste")
			(net "P3V3_STBY_P1V5_LAN_I210")
			(options
				(clearance outline)
				(anchor circle)
			)
			(primitives
				(gr_poly
					(pts
						(xy 0.1524 -0.381)
						(arc
							(start 0.1524 0.2286)
							(mid 0 0.381)
							(end -0.1524 0.2286)
						)
						(xy -0.1524 -0.381)
					)
					(width 0)
					(fill yes)
				)
			)
		)
		(pad "52" smd custom
			(at 2.249932 -4.3688 180)
			(size 0.0762 0.0762)
			(layers "F.Cu" "F.Mask" "F.Paste")
			(net "NIC_SET_N_MDI_2_DN")
			(options
				(clearance outline)
				(anchor circle)
			)
			(primitives
				(gr_poly
					(pts
						(xy 0.1524 -0.381)
						(arc
							(start 0.1524 0.2286)
							(mid 0 0.381)
							(end -0.1524 0.2286)
						)
						(xy -0.1524 -0.381)
					)
					(width 0)
					(fill yes)
				)
			)
		)
		(pad "53" smd custom
			(at 1.75006 -4.3688 180)
			(size 0.0762 0.0762)
			(layers "F.Cu" "F.Mask" "F.Paste")
			(net "NIC_SET_P_MDI_2_DP")
			(options
				(clearance outline)
				(anchor circle)
			)
			(primitives
				(gr_poly
					(pts
						(xy 0.1524 -0.381)
						(arc
							(start 0.1524 0.2286)
							(mid 0 0.381)
							(end -0.1524 0.2286)
						)
						(xy -0.1524 -0.381)
					)
					(width 0)
					(fill yes)
				)
			)
		)
		(pad "54" smd custom
			(at 1.249934 -4.3688 180)
			(size 0.0762 0.0762)
			(layers "F.Cu" "F.Mask" "F.Paste")
			(net "NIC_MDI_SPRV_RJ45_1_DN")
			(options
				(clearance outline)
				(anchor circle)
			)
			(primitives
				(gr_poly
					(pts
						(xy 0.1524 -0.381)
						(arc
							(start 0.1524 0.2286)
							(mid 0 0.381)
							(end -0.1524 0.2286)
						)
						(xy -0.1524 -0.381)
					)
					(width 0)
					(fill yes)
				)
			)
		)
		(pad "55" smd custom
			(at 0.750062 -4.3688 180)
			(size 0.0762 0.0762)
			(layers "F.Cu" "F.Mask" "F.Paste")
			(net "NIC_MDI_SPRV_RJ45_1_DP")
			(options
				(clearance outline)
				(anchor circle)
			)
			(primitives
				(gr_poly
					(pts
						(xy 0.1524 -0.381)
						(arc
							(start 0.1524 0.2286)
							(mid 0 0.381)
							(end -0.1524 0.2286)
						)
						(xy -0.1524 -0.381)
					)
					(width 0)
					(fill yes)
				)
			)
		)
		(pad "56" smd custom
			(at 0.249936 -4.3688 180)
			(size 0.0762 0.0762)
			(layers "F.Cu" "F.Mask" "F.Paste")
			(net "P1V5_LAN_I210")
			(options
				(clearance outline)
				(anchor circle)
			)
			(primitives
				(gr_poly
					(pts
						(xy 0.1524 -0.381)
						(arc
							(start 0.1524 0.2286)
							(mid 0 0.381)
							(end -0.1524 0.2286)
						)
						(xy -0.1524 -0.381)
					)
					(width 0)
					(fill yes)
				)
			)
		)
		(pad "57" smd custom
			(at -0.249936 -4.3688 180)
			(size 0.0762 0.0762)
			(layers "F.Cu" "F.Mask" "F.Paste")
			(net "NIC_MDI_SPRV_RJ45_0_DN")
			(options
				(clearance outline)
				(anchor circle)
			)
			(primitives
				(gr_poly
					(pts
						(xy 0.1524 -0.381)
						(arc
							(start 0.1524 0.2286)
							(mid 0 0.381)
							(end -0.1524 0.2286)
						)
						(xy -0.1524 -0.381)
					)
					(width 0)
					(fill yes)
				)
			)
		)
		(pad "58" smd custom
			(at -0.750062 -4.3688 180)
			(size 0.0762 0.0762)
			(layers "F.Cu" "F.Mask" "F.Paste")
			(net "NIC_MDI_SPRV_RJ45_0_DP")
			(options
				(clearance outline)
				(anchor circle)
			)
			(primitives
				(gr_poly
					(pts
						(xy 0.1524 -0.381)
						(arc
							(start 0.1524 0.2286)
							(mid 0 0.381)
							(end -0.1524 0.2286)
						)
						(xy -0.1524 -0.381)
					)
					(width 0)
					(fill yes)
				)
			)
		)
		(pad "59" smd custom
			(at -1.249934 -4.3688 180)
			(size 0.0762 0.0762)
			(layers "F.Cu" "F.Mask" "F.Paste")
			(net "P0V9_LAN")
			(options
				(clearance outline)
				(anchor circle)
			)
			(primitives
				(gr_poly
					(pts
						(xy 0.1524 -0.381)
						(arc
							(start 0.1524 0.2286)
							(mid 0 0.381)
							(end -0.1524 0.2286)
						)
						(xy -0.1524 -0.381)
					)
					(width 0)
					(fill yes)
				)
			)
		)
		(pad "60" smd custom
			(at -1.75006 -4.3688 180)
			(size 0.0762 0.0762)
			(layers "F.Cu" "F.Mask" "F.Paste")
			(net "TP_SPRV_SDP3")
			(options
				(clearance outline)
				(anchor circle)
			)
			(primitives
				(gr_poly
					(pts
						(xy 0.1524 -0.381)
						(arc
							(start 0.1524 0.2286)
							(mid 0 0.381)
							(end -0.1524 0.2286)
						)
						(xy -0.1524 -0.381)
					)
					(width 0)
					(fill yes)
				)
			)
		)
		(pad "61" smd custom
			(at -2.249932 -4.3688 180)
			(size 0.0762 0.0762)
			(layers "F.Cu" "F.Mask" "F.Paste")
			(net "FM_1GB_LOM_DISABLE_N")
			(options
				(clearance outline)
				(anchor circle)
			)
			(primitives
				(gr_poly
					(pts
						(xy 0.1524 -0.381)
						(arc
							(start 0.1524 0.2286)
							(mid 0 0.381)
							(end -0.1524 0.2286)
						)
						(xy -0.1524 -0.381)
					)
					(width 0)
					(fill yes)
				)
			)
		)
		(pad "62" smd custom
			(at -2.750058 -4.3688 180)
			(size 0.0762 0.0762)
			(layers "F.Cu" "F.Mask" "F.Paste")
			(net "TP_SPRV_SDP2")
			(options
				(clearance outline)
				(anchor circle)
			)
			(primitives
				(gr_poly
					(pts
						(xy 0.1524 -0.381)
						(arc
							(start 0.1524 0.2286)
							(mid 0 0.381)
							(end -0.1524 0.2286)
						)
						(xy -0.1524 -0.381)
					)
					(width 0)
					(fill yes)
				)
			)
		)
		(pad "63" smd custom
			(at -3.24993 -4.3688 180)
			(size 0.0762 0.0762)
			(layers "F.Cu" "F.Mask" "F.Paste")
			(net "TP_SPRV_SDP0")
			(options
				(clearance outline)
				(anchor circle)
			)
			(primitives
				(gr_poly
					(pts
						(xy 0.1524 -0.381)
						(arc
							(start 0.1524 0.2286)
							(mid 0 0.381)
							(end -0.1524 0.2286)
						)
						(xy -0.1524 -0.381)
					)
					(width 0)
					(fill yes)
				)
			)
		)
		(pad "64" smd custom
			(at -3.750056 -4.3688 180)
			(size 0.0762 0.0762)
			(layers "F.Cu" "F.Mask" "F.Paste")
			(net "P3V3_STBY")
			(options
				(clearance outline)
				(anchor circle)
			)
			(primitives
				(gr_poly
					(pts
						(xy 0.1524 -0.381)
						(arc
							(start 0.1524 0.2286)
							(mid 0 0.381)
							(end -0.1524 0.2286)
						)
						(xy -0.1524 -0.381)
					)
					(width 0)
					(fill yes)
				)
			)
		)
		(pad "65" smd rect
			(at 0 0 180)
			(size 3.6068 3.6068)
			(layers "F.Cu" "F.Mask" "F.Paste")
			(net "GND")
		)
	)
)
